# S9S_MB_2U (Grand Teton) — schematic netlist excerpt (pin names and nets, part order shuffled) for the footprints in the layout excerpt that follows; sources: Cadence DE-HDL packaged netlist, KiCad conversion of 03242023_DA0F0TMBIJ0_F0T_Motherboard_J_brd_V01_OCP.brd

C1020  Q_CAP  22UF 4V 20% X6S  pkg C0402  page 74 : A = PVCCIN_CPU0 ; B = GND
PL5  Q_INDUCTOR  120NH/69A IND  pkg SMLF  page 275 : \1\ = SW_PVCCINFAON_CPU0_SW2 ; \2\ = PVCCINFAON_CPU0
R4697  Q_RES  0 5% CHIP  pkg 0402LF  page 213 : A = RST_SRST_PLD_BMC_R_N ; B = RST_SRST_PLD_BMC_N

(kicad_pcb
	(version 20260206)
	(generator "pcbnew")
	(generator_version "10.0")
	(general
		(thickness 1.6)
		(legacy_teardrops no)
	)
	(paper "A4")
	(title_block
		(title "03242023_DA0F0TMBIJ0_F0T_Motherboard_J_brd_V01_OCP.brd")
		(comment 1 "Grand Teton / footprints 1163-1165 of 6105")
	)
	(layers
		(0 "F.Cu" signal "TOP")
		(4 "In1.Cu" signal "GND")
		(6 "In2.Cu" signal "IN1")
		(8 "In3.Cu" signal "GND1")
		(10 "In4.Cu" signal "IN2")
		(12 "In5.Cu" signal "GND2")
		(14 "In6.Cu" signal "IN3")
		(16 "In7.Cu" signal "GND3")
		(18 "In8.Cu" signal "VCC")
		(20 "In9.Cu" signal "VCC1")
		(22 "In10.Cu" signal "GND4")
		(24 "In11.Cu" signal "IN4")
		(26 "In12.Cu" signal "GND5")
		(28 "In13.Cu" signal "IN5")
		(30 "In14.Cu" signal "GND6")
		(32 "In15.Cu" signal "IN6")
		(34 "In16.Cu" signal "GND7")
		(2 "B.Cu" signal "BOTTOM")
		(9 "F.Adhes" user "F.Adhesive")
		(11 "B.Adhes" user "B.Adhesive")
		(13 "F.Paste" user "Package Geometry/Pastemask Top")
		(15 "B.Paste" user "Package Geometry/Pastemask Bottom")
		(5 "F.SilkS" user "Ref Des/Silkscreen Top")
		(7 "B.SilkS" user "Ref Des/Silkscreen Bottom")
		(1 "F.Mask" user "Board Geometry/Soldermask Top")
		(3 "B.Mask" user "Board Geometry/Soldermask Bottom")
		(17 "Dwgs.User" user "User.Drawings")
		(19 "Cmts.User" user "User.Comments")
		(21 "Eco1.User" user "User.Eco1")
		(23 "Eco2.User" user "User.Eco2")
		(25 "Edge.Cuts" user "Board Geometry/Outline")
		(27 "Margin" user)
		(31 "F.CrtYd" user "Package Geometry/Place Bound Top")
		(29 "B.CrtYd" user "Package Geometry/Place Bound Bottom")
		(35 "F.Fab" user "Ref Des/Assembly Top")
		(33 "B.Fab" user "Ref Des/Assembly Bottom")
	)
	(footprint ""
		(layer "F.Cu")
		(at 365.46663 -252.956314 -90)
		(property "Reference" "C1020"
			(at 0 0 270)
			(layer "F.SilkS")
			(hide yes)
			(effects
				(font
					(size 1.27 1.27)
				)
			)
		)
		(property "Value" ""
			(at 0 0 270)
			(layer "F.Fab")
			(effects
				(font
					(size 1.27 1.27)
				)
			)
		)
		(duplicate_pad_numbers_are_jumpers no)
		(fp_line
			(start -0.7874 0.4064)
			(end -0.7874 -0.4064)
			(stroke
				(width 0.1524)
				(type default)
			)
			(layer "F.SilkS")
		)
		(fp_line
			(start 0.7874 0.4064)
			(end -0.7874 0.4064)
			(stroke
				(width 0.1524)
				(type default)
			)
			(layer "F.SilkS")
		)
		(fp_line
			(start -0.7874 -0.4064)
			(end 0.7874 -0.4064)
			(stroke
				(width 0.1524)
				(type default)
			)
			(layer "F.SilkS")
		)
		(fp_line
			(start 0.7874 -0.4064)
			(end 0.7874 0.4064)
			(stroke
				(width 0.1524)
				(type default)
			)
			(layer "F.SilkS")
		)
		(fp_line
			(start -0.67945 0.3048)
			(end -0.67945 -0.305054)
			(stroke
				(width 0.1)
				(type default)
			)
			(layer "F.Fab")
		)
		(fp_line
			(start -0.12065 0.3048)
			(end -0.67945 0.3048)
			(stroke
				(width 0.1)
				(type default)
			)
			(layer "F.Fab")
		)
		(fp_line
			(start 0.120396 0.3048)
			(end 0.120396 0.2794)
			(stroke
				(width 0.1)
				(type default)
			)
			(layer "F.Fab")
		)
		(fp_line
			(start 0.67945 0.3048)
			(end 0.120396 0.3048)
			(stroke
				(width 0.1)
				(type default)
			)
			(layer "F.Fab")
		)
		(fp_line
			(start -0.12065 0.2794)
			(end -0.12065 0.3048)
			(stroke
				(width 0.1)
				(type default)
			)
			(layer "F.Fab")
		)
		(fp_line
			(start 0.120396 0.2794)
			(end -0.12065 0.2794)
			(stroke
				(width 0.1)
				(type default)
			)
			(layer "F.Fab")
		)
		(fp_line
			(start -0.12065 -0.2794)
			(end 0.12065 -0.2794)
			(stroke
				(width 0.1)
				(type default)
			)
			(layer "F.Fab")
		)
		(fp_line
			(start 0.12065 -0.2794)
			(end 0.12065 -0.3048)
			(stroke
				(width 0.1)
				(type default)
			)
			(layer "F.Fab")
		)
		(fp_line
			(start 0.12065 -0.3048)
			(end 0.67945 -0.3048)
			(stroke
				(width 0.1)
				(type default)
			)
			(layer "F.Fab")
		)
		(fp_line
			(start 0.67945 -0.3048)
			(end 0.67945 0.3048)
			(stroke
				(width 0.1)
				(type default)
			)
			(layer "F.Fab")
		)
		(fp_line
			(start -0.67945 -0.305054)
			(end -0.12065 -0.305054)
			(stroke
				(width 0.1)
				(type default)
			)
			(layer "F.Fab")
		)
		(fp_line
			(start -0.12065 -0.305054)
			(end -0.12065 -0.2794)
			(stroke
				(width 0.1)
				(type default)
			)
			(layer "F.Fab")
		)
		(pad "1" smd circle
			(at -0.40005 0 270)
			(size 0 0)
			(layers "F.Cu" "F.Mask" "F.Paste")
			(net "PVCCIN_CPU0")
		)
		(pad "2" smd circle
			(at 0.40005 0 270)
			(size 0 0)
			(layers "F.Cu" "F.Mask" "F.Paste")
			(net "GND")
		)
	)
	(footprint ""
		(layer "F.Cu")
		(at 152.755346 -115.4684 180)
		(property "Reference" "R4697"
			(at 0 0 180)
			(layer "F.SilkS")
			(hide yes)
			(effects
				(font
					(size 1.27 1.27)
				)
			)
		)
		(property "Value" ""
			(at 0 0 180)
			(layer "F.Fab")
			(effects
				(font
					(size 1.27 1.27)
				)
			)
		)
		(duplicate_pad_numbers_are_jumpers no)
		(fp_line
			(start 0.7874 0.4064)
			(end -0.7874 0.4064)
			(stroke
				(width 0.1524)
				(type default)
			)
			(layer "F.SilkS")
		)
		(fp_line
			(start 0.7874 -0.4064)
			(end 0.7874 0.4064)
			(stroke
				(width 0.1524)
				(type default)
			)
			(layer "F.SilkS")
		)
		(fp_line
			(start -0.7874 0.4064)
			(end -0.7874 -0.4064)
			(stroke
				(width 0.1524)
				(type default)
			)
			(layer "F.SilkS")
		)
		(fp_line
			(start -0.7874 -0.4064)
			(end 0.7874 -0.4064)
			(stroke
				(width 0.1524)
				(type default)
			)
			(layer "F.SilkS")
		)
		(fp_line
			(start 0.67945 0.3048)
			(end 0.120396 0.3048)
			(stroke
				(width 0.1)
				(type default)
			)
			(layer "F.Fab")
		)
		(fp_line
			(start 0.67945 -0.3048)
			(end 0.67945 0.3048)
			(stroke
				(width 0.1)
				(type default)
			)
			(layer "F.Fab")
		)
		(fp_line
			(start 0.12065 -0.2794)
			(end 0.12065 -0.3048)
			(stroke
				(width 0.1)
				(type default)
			)
			(layer "F.Fab")
		)
		(fp_line
			(start 0.12065 -0.3048)
			(end 0.67945 -0.3048)
			(stroke
				(width 0.1)
				(type default)
			)
			(layer "F.Fab")
		)
		(fp_line
			(start 0.120396 0.3048)
			(end 0.120396 0.2794)
			(stroke
				(width 0.1)
				(type default)
			)
			(layer "F.Fab")
		)
		(fp_line
			(start 0.120396 0.2794)
			(end -0.12065 0.2794)
			(stroke
				(width 0.1)
				(type default)
			)
			(layer "F.Fab")
		)
		(fp_line
			(start -0.12065 0.3048)
			(end -0.67945 0.3048)
			(stroke
				(width 0.1)
				(type default)
			)
			(layer "F.Fab")
		)
		(fp_line
			(start -0.12065 0.2794)
			(end -0.12065 0.3048)
			(stroke
				(width 0.1)
				(type default)
			)
			(layer "F.Fab")
		)
		(fp_line
			(start -0.12065 -0.2794)
			(end 0.12065 -0.2794)
			(stroke
				(width 0.1)
				(type default)
			)
			(layer "F.Fab")
		)
		(fp_line
			(start -0.12065 -0.305054)
			(end -0.12065 -0.2794)
			(stroke
				(width 0.1)
				(type default)
			)
			(layer "F.Fab")
		)
		(fp_line
			(start -0.67945 0.3048)
			(end -0.67945 -0.305054)
			(stroke
				(width 0.1)
				(type default)
			)
			(layer "F.Fab")
		)
		(fp_line
			(start -0.67945 -0.305054)
			(end -0.12065 -0.305054)
			(stroke
				(width 0.1)
				(type default)
			)
			(layer "F.Fab")
		)
		(pad "1" smd circle
			(at -0.40005 0 180)
			(size 0 0)
			(layers "F.Cu" "F.Mask" "F.Paste")
			(net "RST_SRST_PLD_BMC_R_N")
		)
		(pad "2" smd circle
			(at 0.40005 0 180)
			(size 0 0)
			(layers "F.Cu" "F.Mask" "F.Paste")
			(net "RST_SRST_PLD_BMC_N")
		)
	)
	(footprint ""
		(layer "F.Cu")
		(at 408.554682 -179.457858 180)
		(property "Reference" "PL5"
			(at 5.785104 -0.050292 0)
			(unlocked yes)
			(layer "F.SilkS")
			(effects
				(font
					(size 0.7874 0.5842)
					(thickness 0.1524)
				)
				(justify left)
			)
		)
		(property "Value" ""
			(at 0 0 180)
			(layer "F.Fab")
			(effects
				(font
					(size 1.27 1.27)
				)
			)
		)
		(duplicate_pad_numbers_are_jumpers no)
		(fp_line
			(start 3.24993 3.24993)
			(end -3.24993 3.24993)
			(stroke
				(width 0.1524)
				(type default)
			)
			(layer "F.SilkS")
		)
		(fp_line
			(start 3.24993 2.2352)
			(end 3.24993 3.24993)
			(stroke
				(width 0.1524)
				(type default)
			)
			(layer "F.SilkS")
		)
		(fp_line
			(start 3.24993 -3.24993)
			(end 3.24993 -2.2352)
			(stroke
				(width 0.1524)
				(type default)
			)
			(layer "F.SilkS")
		)
		(fp_line
			(start -3.24993 3.24993)
			(end -3.24993 2.2352)
			(stroke
				(width 0.1524)
				(type default)
			)
			(layer "F.SilkS")
		)
		(fp_line
			(start -3.24993 -2.2352)
			(end -3.24993 -3.24993)
			(stroke
				(width 0.1524)
				(type default)
			)
			(layer "F.SilkS")
		)
		(fp_line
			(start -3.24993 -3.24993)
			(end 3.24993 -3.24993)
			(stroke
				(width 0.1524)
				(type default)
			)
			(layer "F.SilkS")
		)
		(fp_line
			(start 3.24993 3.24993)
			(end -3.24993 3.24993)
			(stroke
				(width 0.1)
				(type default)
			)
			(layer "F.Fab")
		)
		(fp_line
			(start 3.24993 -3.24993)
			(end 3.24993 3.24993)
			(stroke
				(width 0.1)
				(type default)
			)
			(layer "F.Fab")
		)
		(fp_line
			(start -3.24993 3.24993)
			(end -3.24993 -3.24993)
			(stroke
				(width 0.1)
				(type default)
			)
			(layer "F.Fab")
		)
		(fp_line
			(start -3.24993 -3.24993)
			(end 3.24993 -3.24993)
			(stroke
				(width 0.1)
				(type default)
			)
			(layer "F.Fab")
		)
		(pad "1" smd rect
			(at -2.29997 0 180)
			(size 2.0066 4.2164)
			(layers "F.Cu" "F.Mask" "F.Paste")
			(net "SW_PVCCINFAON_CPU0_SW2")
		)
		(pad "2" smd rect
			(at 2.29997 0 180)
			(size 2.0066 4.2164)
			(layers "F.Cu" "F.Mask" "F.Paste")
			(net "PVCCINFAON_CPU0")
		)
	)
)
